(kicad_pcb
	(version 20260206)
	(generator "pcbnew")
	(generator_version "10.0")
	(general
		(thickness 1.6)
		(legacy_teardrops no)
	)
	(paper "A4")
	(title_block
		(title "01162023_DA0F0TEBIF0_F0T_Expander_BD_F_brd_V02_OCP.brd")
		(comment 1 "Grand Teton / footprints 1149-1156 of 9728")
	)
	(layers
		(0 "F.Cu" signal "TOP")
		(4 "In1.Cu" signal "GND")
		(6 "In2.Cu" signal "VCC")
		(8 "In3.Cu" signal "VCC1")
		(10 "In4.Cu" signal "GND1")
		(12 "In5.Cu" signal "IN1")
		(14 "In6.Cu" signal "GND2")
		(16 "In7.Cu" signal "IN2")
		(18 "In8.Cu" signal "GND3")
		(20 "In9.Cu" signal "IN3")
		(22 "In10.Cu" signal "GND4")
		(24 "In11.Cu" signal "IN4")
		(26 "In12.Cu" signal "GND5")
		(28 "In13.Cu" signal "IN5")
		(30 "In14.Cu" signal "GND6")
		(32 "In15.Cu" signal "IN6")
		(34 "In16.Cu" signal "GND7")
		(2 "B.Cu" signal "BOTTOM")
		(9 "F.Adhes" user "F.Adhesive")
		(11 "B.Adhes" user "B.Adhesive")
		(13 "F.Paste" user "Package Geometry/Pastemask Top")
		(15 "B.Paste" user "Package Geometry/Pastemask Bottom")
		(5 "F.SilkS" user "Ref Des/Silkscreen Top")
		(7 "B.SilkS" user "Ref Des/Silkscreen Bottom")
		(1 "F.Mask" user "Board Geometry/Soldermask Top")
		(3 "B.Mask" user "Board Geometry/Soldermask Bottom")
		(17 "Dwgs.User" user "User.Drawings")
		(19 "Cmts.User" user "User.Comments")
		(21 "Eco1.User" user "User.Eco1")
		(23 "Eco2.User" user "User.Eco2")
		(25 "Edge.Cuts" user "Board Geometry/Outline")
		(27 "Margin" user)
		(31 "F.CrtYd" user "Package Geometry/Place Bound Top")
		(29 "B.CrtYd" user "Package Geometry/Place Bound Bottom")
		(35 "F.Fab" user "Ref Des/Assembly Top")
		(33 "B.Fab" user "Ref Des/Assembly Bottom")
	)
	(footprint ""
		(layer "F.Cu")
		(at 152.461468 -391.18159 -90)
		(property "Reference" "C4052"
			(at 0 0 270)
			(layer "F.SilkS")
			(hide yes)
			(effects
				(font
					(size 1.27 1.27)
				)
			)
		)
		(property "Value" ""
			(at 0 0 270)
			(layer "F.Fab")
			(effects
				(font
					(size 1.27 1.27)
				)
			)
		)
		(duplicate_pad_numbers_are_jumpers no)
		(fp_line
			(start -0.7874 0.4064)
			(end -0.7874 -0.4064)
			(stroke
				(width 0.1524)
				(type default)
			)
			(layer "F.SilkS")
		)
		(fp_line
			(start 0.7874 0.4064)
			(end -0.7874 0.4064)
			(stroke
				(width 0.1524)
				(type default)
			)
			(layer "F.SilkS")
		)
		(fp_line
			(start -0.7874 -0.4064)
			(end 0.7874 -0.4064)
			(stroke
				(width 0.1524)
				(type default)
			)
			(layer "F.SilkS")
		)
		(fp_line
			(start 0.7874 -0.4064)
			(end 0.7874 0.4064)
			(stroke
				(width 0.1524)
				(type default)
			)
			(layer "F.SilkS")
		)
		(fp_line
			(start -0.67945 0.3048)
			(end -0.67945 -0.305054)
			(stroke
				(width 0.1)
				(type default)
			)
			(layer "F.Fab")
		)
		(fp_line
			(start -0.12065 0.3048)
			(end -0.67945 0.3048)
			(stroke
				(width 0.1)
				(type default)
			)
			(layer "F.Fab")
		)
		(fp_line
			(start 0.120396 0.3048)
			(end 0.120396 0.2794)
			(stroke
				(width 0.1)
				(type default)
			)
			(layer "F.Fab")
		)
		(fp_line
			(start 0.67945 0.3048)
			(end 0.120396 0.3048)
			(stroke
				(width 0.1)
				(type default)
			)
			(layer "F.Fab")
		)
		(fp_line
			(start -0.12065 0.2794)
			(end -0.12065 0.3048)
			(stroke
				(width 0.1)
				(type default)
			)
			(layer "F.Fab")
		)
		(fp_line
			(start 0.120396 0.2794)
			(end -0.12065 0.2794)
			(stroke
				(width 0.1)
				(type default)
			)
			(layer "F.Fab")
		)
		(fp_line
			(start -0.12065 -0.2794)
			(end 0.12065 -0.2794)
			(stroke
				(width 0.1)
				(type default)
			)
			(layer "F.Fab")
		)
		(fp_line
			(start 0.12065 -0.2794)
			(end 0.12065 -0.3048)
			(stroke
				(width 0.1)
				(type default)
			)
			(layer "F.Fab")
		)
		(fp_line
			(start 0.12065 -0.3048)
			(end 0.67945 -0.3048)
			(stroke
				(width 0.1)
				(type default)
			)
			(layer "F.Fab")
		)
		(fp_line
			(start 0.67945 -0.3048)
			(end 0.67945 0.3048)
			(stroke
				(width 0.1)
				(type default)
			)
			(layer "F.Fab")
		)
		(fp_line
			(start -0.67945 -0.305054)
			(end -0.12065 -0.305054)
			(stroke
				(width 0.1)
				(type default)
			)
			(layer "F.Fab")
		)
		(fp_line
			(start -0.12065 -0.305054)
			(end -0.12065 -0.2794)
			(stroke
				(width 0.1)
				(type default)
			)
			(layer "F.Fab")
		)
		(pad "1" smd circle
			(at -0.40005 0 270)
			(size 0 0)
			(layers "F.Cu" "F.Mask" "F.Paste")
			(net "GND")
		)
		(pad "2" smd circle
			(at 0.40005 0 270)
			(size 0 0)
			(layers "F.Cu" "F.Mask" "F.Paste")
			(net "GPU_FPGA_EROT_RECOV_N")
		)
	)
	(footprint ""
		(layer "F.Cu")
		(at 371.16258 -343.952322 90)
		(property "Reference" "C762"
			(at 0 0 90)
			(layer "F.SilkS")
			(hide yes)
			(effects
				(font
					(size 1.27 1.27)
				)
			)
		)
		(property "Value" ""
			(at 0 0 90)
			(layer "F.Fab")
			(effects
				(font
					(size 1.27 1.27)
				)
			)
		)
		(duplicate_pad_numbers_are_jumpers no)
		(fp_line
			(start 0.299974 -0.150114)
			(end 0.299974 0.150114)
			(stroke
				(width 0.1)
				(type default)
			)
			(layer "F.Fab")
		)
		(fp_line
			(start -0.299974 -0.150114)
			(end 0.299974 -0.150114)
			(stroke
				(width 0.1)
				(type default)
			)
			(layer "F.Fab")
		)
		(fp_line
			(start 0.299974 0.150114)
			(end -0.299974 0.150114)
			(stroke
				(width 0.1)
				(type default)
			)
			(layer "F.Fab")
		)
		(fp_line
			(start -0.299974 0.150114)
			(end -0.299974 -0.150114)
			(stroke
				(width 0.1)
				(type default)
			)
			(layer "F.Fab")
		)
		(pad "1" smd rect
			(at -0.2667 0 90)
			(size 0.3048 0.381)
			(layers "F.Cu" "F.Mask" "F.Paste")
			(net "P5E_PEX3_STN6_TX_DP<111>")
		)
		(pad "2" smd rect
			(at 0.2667 0 90)
			(size 0.3048 0.381)
			(layers "F.Cu" "F.Mask" "F.Paste")
			(net "P5E_PEX3_STN6_TX_C_DP<111>")
		)
	)
	(footprint ""
		(layer "F.Cu")
		(at 326.30237 -227.711 90)
		(property "Reference" "R6177"
			(at 0 0 90)
			(layer "F.SilkS")
			(hide yes)
			(effects
				(font
					(size 1.27 1.27)
				)
			)
		)
		(property "Value" ""
			(at 0 0 90)
			(layer "F.Fab")
			(effects
				(font
					(size 1.27 1.27)
				)
			)
		)
		(duplicate_pad_numbers_are_jumpers no)
		(fp_line
			(start 0.7874 -0.4064)
			(end 0.7874 0.4064)
			(stroke
				(width 0.1524)
				(type default)
			)
			(layer "F.SilkS")
		)
		(fp_line
			(start -0.7874 -0.4064)
			(end 0.7874 -0.4064)
			(stroke
				(width 0.1524)
				(type default)
			)
			(layer "F.SilkS")
		)
		(fp_line
			(start 0.7874 0.4064)
			(end -0.7874 0.4064)
			(stroke
				(width 0.1524)
				(type default)
			)
			(layer "F.SilkS")
		)
		(fp_line
			(start -0.7874 0.4064)
			(end -0.7874 -0.4064)
			(stroke
				(width 0.1524)
				(type default)
			)
			(layer "F.SilkS")
		)
		(fp_line
			(start -0.12065 -0.305054)
			(end -0.12065 -0.2794)
			(stroke
				(width 0.1)
				(type default)
			)
			(layer "F.Fab")
		)
		(fp_line
			(start -0.67945 -0.305054)
			(end -0.12065 -0.305054)
			(stroke
				(width 0.1)
				(type default)
			)
			(layer "F.Fab")
		)
		(fp_line
			(start 0.67945 -0.3048)
			(end 0.67945 0.3048)
			(stroke
				(width 0.1)
				(type default)
			)
			(layer "F.Fab")
		)
		(fp_line
			(start 0.12065 -0.3048)
			(end 0.67945 -0.3048)
			(stroke
				(width 0.1)
				(type default)
			)
			(layer "F.Fab")
		)
		(fp_line
			(start 0.12065 -0.2794)
			(end 0.12065 -0.3048)
			(stroke
				(width 0.1)
				(type default)
			)
			(layer "F.Fab")
		)
		(fp_line
			(start -0.12065 -0.2794)
			(end 0.12065 -0.2794)
			(stroke
				(width 0.1)
				(type default)
			)
			(layer "F.Fab")
		)
		(fp_line
			(start 0.120396 0.2794)
			(end -0.12065 0.2794)
			(stroke
				(width 0.1)
				(type default)
			)
			(layer "F.Fab")
		)
		(fp_line
			(start -0.12065 0.2794)
			(end -0.12065 0.3048)
			(stroke
				(width 0.1)
				(type default)
			)
			(layer "F.Fab")
		)
		(fp_line
			(start 0.67945 0.3048)
			(end 0.120396 0.3048)
			(stroke
				(width 0.1)
				(type default)
			)
			(layer "F.Fab")
		)
		(fp_line
			(start 0.120396 0.3048)
			(end 0.120396 0.2794)
			(stroke
				(width 0.1)
				(type default)
			)
			(layer "F.Fab")
		)
		(fp_line
			(start -0.12065 0.3048)
			(end -0.67945 0.3048)
			(stroke
				(width 0.1)
				(type default)
			)
			(layer "F.Fab")
		)
		(fp_line
			(start -0.67945 0.3048)
			(end -0.67945 -0.305054)
			(stroke
				(width 0.1)
				(type default)
			)
			(layer "F.Fab")
		)
		(pad "1" smd circle
			(at -0.40005 0 90)
			(size 0 0)
			(layers "F.Cu" "F.Mask" "F.Paste")
			(net "GND")
		)
		(pad "2" smd circle
			(at 0.40005 0 90)
			(size 0 0)
			(layers "F.Cu" "F.Mask" "F.Paste")
			(net "RST_PEX_SYS_R_N")
		)
	)
	(footprint ""
		(layer "F.Cu")
		(at 68.479162 -350.098614 90)
		(property "Reference" "C122"
			(at 0 0 90)
			(layer "F.SilkS")
			(hide yes)
			(effects
				(font
					(size 1.27 1.27)
				)
			)
		)
		(property "Value" ""
			(at 0 0 90)
			(layer "F.Fab")
			(effects
				(font
					(size 1.27 1.27)
				)
			)
		)
		(duplicate_pad_numbers_are_jumpers no)
		(fp_line
			(start 0.299974 -0.150114)
			(end 0.299974 0.150114)
			(stroke
				(width 0.1)
				(type default)
			)
			(layer "F.Fab")
		)
		(fp_line
			(start -0.299974 -0.150114)
			(end 0.299974 -0.150114)
			(stroke
				(width 0.1)
				(type default)
			)
			(layer "F.Fab")
		)
		(fp_line
			(start 0.299974 0.150114)
			(end -0.299974 0.150114)
			(stroke
				(width 0.1)
				(type default)
			)
			(layer "F.Fab")
		)
		(fp_line
			(start -0.299974 0.150114)
			(end -0.299974 -0.150114)
			(stroke
				(width 0.1)
				(type default)
			)
			(layer "F.Fab")
		)
		(pad "1" smd rect
			(at -0.2667 0 90)
			(size 0.3048 0.381)
			(layers "F.Cu" "F.Mask" "F.Paste")
			(net "P5E_PEX0_STN5_TX_DN<83>")
		)
		(pad "2" smd rect
			(at 0.2667 0 90)
			(size 0.3048 0.381)
			(layers "F.Cu" "F.Mask" "F.Paste")
			(net "P5E_PEX0_STN5_TX_C_DN<83>")
		)
	)
	(footprint ""
		(layer "F.Cu")
		(at 220.36786 -51.019456)
		(property "Reference" "PC399"
			(at 0 0 0)
			(layer "F.SilkS")
			(hide yes)
			(effects
				(font
					(size 1.27 1.27)
				)
			)
		)
		(property "Value" ""
			(at 0 0 0)
			(layer "F.Fab")
			(effects
				(font
					(size 1.27 1.27)
				)
			)
		)
		(duplicate_pad_numbers_are_jumpers no)
		(fp_line
			(start -0.7874 -0.4064)
			(end 0.7874 -0.4064)
			(stroke
				(width 0.1524)
				(type default)
			)
			(layer "F.SilkS")
		)
		(fp_line
			(start -0.7874 0.4064)
			(end -0.7874 -0.4064)
			(stroke
				(width 0.1524)
				(type default)
			)
			(layer "F.SilkS")
		)
		(fp_line
			(start 0.7874 -0.4064)
			(end 0.7874 0.4064)
			(stroke
				(width 0.1524)
				(type default)
			)
			(layer "F.SilkS")
		)
		(fp_line
			(start 0.7874 0.4064)
			(end -0.7874 0.4064)
			(stroke
				(width 0.1524)
				(type default)
			)
			(layer "F.SilkS")
		)
		(fp_line
			(start -0.6858 -0.3048)
			(end -0.1016 -0.3048)
			(stroke
				(width 0.1)
				(type default)
			)
			(layer "F.Fab")
		)
		(fp_line
			(start -0.6858 0.3048)
			(end -0.6858 -0.3048)
			(stroke
				(width 0.1)
				(type default)
			)
			(layer "F.Fab")
		)
		(fp_line
			(start -0.1016 -0.3048)
			(end -0.1016 -0.2794)
			(stroke
				(width 0.1)
				(type default)
			)
			(layer "F.Fab")
		)
		(fp_line
			(start -0.1016 -0.2794)
			(end 0.1016 -0.2794)
			(stroke
				(width 0.1)
				(type default)
			)
			(layer "F.Fab")
		)
		(fp_line
			(start -0.1016 0.2794)
			(end -0.1016 0.3048)
			(stroke
				(width 0.1)
				(type default)
			)
			(layer "F.Fab")
		)
		(fp_line
			(start -0.1016 0.3048)
			(end -0.6858 0.3048)
			(stroke
				(width 0.1)
				(type default)
			)
			(layer "F.Fab")
		)
		(fp_line
			(start 0.1016 -0.3048)
			(end 0.6858 -0.3048)
			(stroke
				(width 0.1)
				(type default)
			)
			(layer "F.Fab")
		)
		(fp_line
			(start 0.1016 -0.2794)
			(end 0.1016 -0.3048)
			(stroke
				(width 0.1)
				(type default)
			)
			(layer "F.Fab")
		)
		(fp_line
			(start 0.1016 0.2794)
			(end -0.1016 0.2794)
			(stroke
				(width 0.1)
				(type default)
			)
			(layer "F.Fab")
		)
		(fp_line
			(start 0.1016 0.3048)
			(end 0.1016 0.2794)
			(stroke
				(width 0.1)
				(type default)
			)
			(layer "F.Fab")
		)
		(fp_line
			(start 0.6858 -0.3048)
			(end 0.6858 0.3048)
			(stroke
				(width 0.1)
				(type default)
			)
			(layer "F.Fab")
		)
		(fp_line
			(start 0.6858 0.3048)
			(end 0.1016 0.3048)
			(stroke
				(width 0.1)
				(type default)
			)
			(layer "F.Fab")
		)
		(pad "1" smd rect
			(at -0.40005 0 180)
			(size 0.4572 0.508)
			(layers "F.Cu" "F.Mask" "F.Paste")
			(net "P12V_SSD7_SS")
		)
		(pad "2" smd rect
			(at 0.40005 0 180)
			(size 0.4572 0.508)
			(layers "F.Cu" "F.Mask" "F.Paste")
			(net "GND")
		)
	)
	(footprint ""
		(layer "F.Cu")
		(at 276.039834 -70.52437 90)
		(property "Reference" "PC864"
			(at 0 0 90)
			(layer "F.SilkS")
			(hide yes)
			(effects
				(font
					(size 1.27 1.27)
				)
			)
		)
		(property "Value" ""
			(at 0 0 90)
			(layer "F.Fab")
			(effects
				(font
					(size 1.27 1.27)
				)
			)
		)
		(duplicate_pad_numbers_are_jumpers no)
		(fp_line
			(start 1.524 -0.762)
			(end 1.524 0.762)
			(stroke
				(width 0.1524)
				(type default)
			)
			(layer "F.SilkS")
		)
		(fp_line
			(start -1.524 -0.762)
			(end 1.524 -0.762)
			(stroke
				(width 0.1524)
				(type default)
			)
			(layer "F.SilkS")
		)
		(fp_line
			(start 1.524 0.762)
			(end -1.524 0.762)
			(stroke
				(width 0.1524)
				(type default)
			)
			(layer "F.SilkS")
		)
		(fp_line
			(start -1.524 0.762)
			(end -1.524 -0.762)
			(stroke
				(width 0.1524)
				(type default)
			)
			(layer "F.SilkS")
		)
		(fp_line
			(start 1.1049 -0.724916)
			(end -1.1049 -0.724916)
			(stroke
				(width 0.1)
				(type default)
			)
			(layer "F.Fab")
		)
		(fp_line
			(start -1.1049 -0.724916)
			(end -1.1049 0.724916)
			(stroke
				(width 0.1)
				(type default)
			)
			(layer "F.Fab")
		)
		(fp_line
			(start 1.1049 0.724916)
			(end 1.1049 -0.724916)
			(stroke
				(width 0.1)
				(type default)
			)
			(layer "F.Fab")
		)
		(fp_line
			(start -1.1049 0.724916)
			(end 1.1049 0.724916)
			(stroke
				(width 0.1)
				(type default)
			)
			(layer "F.Fab")
		)
		(pad "1" smd rect
			(at -0.889 0 270)
			(size 1.016 1.27)
			(layers "F.Cu" "F.Mask" "F.Paste")
			(net "P12V_SSD9_R")
		)
		(pad "2" smd rect
			(at 0.889 0 270)
			(size 1.016 1.27)
			(layers "F.Cu" "F.Mask" "F.Paste")
			(net "GND")
		)
	)
	(footprint ""
		(layer "F.Cu")
		(at 58.684922 -383.652268 180)
		(property "Reference" "R1802"
			(at 0 0 180)
			(layer "F.SilkS")
			(hide yes)
			(effects
				(font
					(size 1.27 1.27)
				)
			)
		)
		(property "Value" ""
			(at 0 0 180)
			(layer "F.Fab")
			(effects
				(font
					(size 1.27 1.27)
				)
			)
		)
		(duplicate_pad_numbers_are_jumpers no)
		(fp_line
			(start 0.7874 0.4064)
			(end -0.7874 0.4064)
			(stroke
				(width 0.1524)
				(type default)
			)
			(layer "F.SilkS")
		)
		(fp_line
			(start 0.7874 -0.4064)
			(end 0.7874 0.4064)
			(stroke
				(width 0.1524)
				(type default)
			)
			(layer "F.SilkS")
		)
		(fp_line
			(start -0.7874 0.4064)
			(end -0.7874 -0.4064)
			(stroke
				(width 0.1524)
				(type default)
			)
			(layer "F.SilkS")
		)
		(fp_line
			(start -0.7874 -0.4064)
			(end 0.7874 -0.4064)
			(stroke
				(width 0.1524)
				(type default)
			)
			(layer "F.SilkS")
		)
		(fp_line
			(start 0.67945 0.3048)
			(end 0.120396 0.3048)
			(stroke
				(width 0.1)
				(type default)
			)
			(layer "F.Fab")
		)
		(fp_line
			(start 0.67945 -0.3048)
			(end 0.67945 0.3048)
			(stroke
				(width 0.1)
				(type default)
			)
			(layer "F.Fab")
		)
		(fp_line
			(start 0.12065 -0.2794)
			(end 0.12065 -0.3048)
			(stroke
				(width 0.1)
				(type default)
			)
			(layer "F.Fab")
		)
		(fp_line
			(start 0.12065 -0.3048)
			(end 0.67945 -0.3048)
			(stroke
				(width 0.1)
				(type default)
			)
			(layer "F.Fab")
		)
		(fp_line
			(start 0.120396 0.3048)
			(end 0.120396 0.2794)
			(stroke
				(width 0.1)
				(type default)
			)
			(layer "F.Fab")
		)
		(fp_line
			(start 0.120396 0.2794)
			(end -0.12065 0.2794)
			(stroke
				(width 0.1)
				(type default)
			)
			(layer "F.Fab")
		)
		(fp_line
			(start -0.12065 0.3048)
			(end -0.67945 0.3048)
			(stroke
				(width 0.1)
				(type default)
			)
			(layer "F.Fab")
		)
		(fp_line
			(start -0.12065 0.2794)
			(end -0.12065 0.3048)
			(stroke
				(width 0.1)
				(type default)
			)
			(layer "F.Fab")
		)
		(fp_line
			(start -0.12065 -0.2794)
			(end 0.12065 -0.2794)
			(stroke
				(width 0.1)
				(type default)
			)
			(layer "F.Fab")
		)
		(fp_line
			(start -0.12065 -0.305054)
			(end -0.12065 -0.2794)
			(stroke
				(width 0.1)
				(type default)
			)
			(layer "F.Fab")
		)
		(fp_line
			(start -0.67945 0.3048)
			(end -0.67945 -0.305054)
			(stroke
				(width 0.1)
				(type default)
			)
			(layer "F.Fab")
		)
		(fp_line
			(start -0.67945 -0.305054)
			(end -0.12065 -0.305054)
			(stroke
				(width 0.1)
				(type default)
			)
			(layer "F.Fab")
		)
		(pad "1" smd circle
			(at -0.40005 0 180)
			(size 0 0)
			(layers "F.Cu" "F.Mask" "F.Paste")
			(net "PRSNT_SWB_C_N")
		)
		(pad "2" smd circle
			(at 0.40005 0 180)
			(size 0 0)
			(layers "F.Cu" "F.Mask" "F.Paste")
			(net "GND")
		)
	)
	(footprint ""
		(layer "F.Cu")
		(at 400.05762 -350.098614 90)
		(property "Reference" "C735"
			(at 0 0 90)
			(layer "F.SilkS")
			(hide yes)
			(effects
				(font
					(size 1.27 1.27)
				)
			)
		)
		(property "Value" ""
			(at 0 0 90)
			(layer "F.Fab")
			(effects
				(font
					(size 1.27 1.27)
				)
			)
		)
		(duplicate_pad_numbers_are_jumpers no)
		(fp_line
			(start 0.299974 -0.150114)
			(end 0.299974 0.150114)
			(stroke
				(width 0.1)
				(type default)
			)
			(layer "F.Fab")
		)
		(fp_line
			(start -0.299974 -0.150114)
			(end 0.299974 -0.150114)
			(stroke
				(width 0.1)
				(type default)
			)
			(layer "F.Fab")
		)
		(fp_line
			(start 0.299974 0.150114)
			(end -0.299974 0.150114)
			(stroke
				(width 0.1)
				(type default)
			)
			(layer "F.Fab")
		)
		(fp_line
			(start -0.299974 0.150114)
			(end -0.299974 -0.150114)
			(stroke
				(width 0.1)
				(type default)
			)
			(layer "F.Fab")
		)
		(pad "1" smd rect
			(at -0.2667 0 90)
			(size 0.3048 0.381)
			(layers "F.Cu" "F.Mask" "F.Paste")
			(net "P5E_PEX3_STN5_TX_DN<93>")
		)
		(pad "2" smd rect
			(at 0.2667 0 90)
			(size 0.3048 0.381)
			(layers "F.Cu" "F.Mask" "F.Paste")
			(net "P5E_PEX3_STN5_TX_C_DN<93>")
		)
	)
)
